(kicad_pcb
	(version 20260206)
	(generator "pcbnew")
	(generator_version "10.0")
	(general
		(thickness 1.6)
		(legacy_teardrops no)
	)
	(paper "A4")
	(title_block
		(title "Wiwynn_Tioga_Pass_MB.brd")
		(comment 1 "Tioga Pass / footprints 1842-1848 of 4770")
	)
	(layers
		(0 "F.Cu" signal "TOP")
		(4 "In1.Cu" signal "L2GND")
		(6 "In2.Cu" signal "L3")
		(8 "In3.Cu" signal "L4GND")
		(10 "In4.Cu" signal "L5")
		(12 "In5.Cu" signal "L6GND")
		(14 "In6.Cu" signal "L7VCC")
		(16 "In7.Cu" signal "L8VCC")
		(18 "In8.Cu" signal "L9GND")
		(20 "In9.Cu" signal "L10")
		(22 "In10.Cu" signal "L11GND")
		(24 "In11.Cu" signal "L12")
		(26 "In12.Cu" signal "L13GND")
		(2 "B.Cu" signal "BOTTOM")
		(9 "F.Adhes" user "F.Adhesive")
		(11 "B.Adhes" user "B.Adhesive")
		(13 "F.Paste" user "Package Geometry/Pastemask Top")
		(15 "B.Paste" user "Package Geometry/Pastemask Bottom")
		(5 "F.SilkS" user "Ref Des/Silkscreen Top")
		(7 "B.SilkS" user "Ref Des/Silkscreen Bottom")
		(1 "F.Mask" user "Board Geometry/Soldermask Top")
		(3 "B.Mask" user "Board Geometry/Soldermask Bottom")
		(17 "Dwgs.User" user "User.Drawings")
		(19 "Cmts.User" user "User.Comments")
		(21 "Eco1.User" user "User.Eco1")
		(23 "Eco2.User" user "User.Eco2")
		(25 "Edge.Cuts" user "Board Geometry/Outline")
		(27 "Margin" user)
		(31 "F.CrtYd" user "Package Geometry/Place Bound Top")
		(29 "B.CrtYd" user "Package Geometry/Place Bound Bottom")
		(35 "F.Fab" user "Ref Des/Assembly Top")
		(33 "B.Fab" user "Ref Des/Assembly Bottom")
	)
	(footprint ""
		(layer "F.Cu")
		(at 394.6525 -76.581 90)
		(property "Reference" "R7D31"
			(at 0 0 90)
			(layer "F.SilkS")
			(hide yes)
			(effects
				(font
					(size 1.27 1.27)
				)
			)
		)
		(property "Value" ""
			(at 0 0 90)
			(layer "F.Fab")
			(effects
				(font
					(size 1.27 1.27)
				)
			)
		)
		(duplicate_pad_numbers_are_jumpers no)
		(fp_poly
			(pts
				(xy -0.2794 -0.1016) (xy 0.2794 -0.1016) (xy 0.2794 0.9906) (xy -0.2794 0.9906)
			)
			(stroke
				(width 0)
				(type default)
			)
			(fill no)
			(layer "F.CrtYd")
		)
		(fp_line
			(start 0.2794 -0.1016)
			(end -0.2794 -0.1016)
			(stroke
				(width 0.1)
				(type default)
			)
			(layer "F.Fab")
		)
		(fp_line
			(start -0.2794 -0.1016)
			(end -0.2794 0.9906)
			(stroke
				(width 0.1)
				(type default)
			)
			(layer "F.Fab")
		)
		(fp_line
			(start 0.2794 0.9906)
			(end 0.2794 -0.1016)
			(stroke
				(width 0.1)
				(type default)
			)
			(layer "F.Fab")
		)
		(fp_line
			(start -0.2794 0.9906)
			(end 0.2794 0.9906)
			(stroke
				(width 0.1)
				(type default)
			)
			(layer "F.Fab")
		)
		(pad "1" smd rect
			(at 0 0 90)
			(size 0.508 0.508)
			(layers "F.Cu" "F.Mask" "F.Paste")
			(net "FM_CPU_ERR2_LVT3_R_N")
		)
		(pad "2" smd rect
			(at 0 0.889 90)
			(size 0.508 0.508)
			(layers "F.Cu" "F.Mask" "F.Paste")
			(net "FM_CPU_ERR2_LVT3_N")
		)
		(zone
			(layer "F.Cu")
			(hatch none 0.5)
			(connect_pads
				(clearance 0)
			)
			(min_thickness 0.25)
			(keepout
				(tracks allowed)
				(vias not_allowed)
				(pads allowed)
				(copperpour not_allowed)
				(footprints allowed)
			)
			(placement
				(enabled no)
				(sheetname "")
			)
			(fill
				(thermal_gap 0.5)
				(thermal_bridge_width 0.5)
				(island_removal_mode 0)
			)
			(polygon
				(pts
					(xy 394.9065 -76.327) (xy 394.9065 -76.835) (xy 395.2875 -76.835) (xy 395.2875 -76.327)
				)
			)
		)
		(zone
			(layer "F.Cu")
			(hatch none 0.5)
			(connect_pads
				(clearance 0)
			)
			(min_thickness 0.25)
			(keepout
				(tracks not_allowed)
				(vias allowed)
				(pads allowed)
				(copperpour not_allowed)
				(footprints allowed)
			)
			(placement
				(enabled no)
				(sheetname "")
			)
			(fill
				(thermal_gap 0.5)
				(thermal_bridge_width 0.5)
				(island_removal_mode 0)
			)
			(polygon
				(pts
					(xy 395.2875 -76.327) (xy 395.2875 -76.835) (xy 394.9065 -76.835) (xy 394.9065 -76.327)
				)
			)
		)
	)
	(footprint ""
		(layer "F.Cu")
		(at 253.392432 -12.954 90)
		(property "Reference" "C5G4"
			(at 1.848866 0.752348 90)
			(unlocked yes)
			(layer "F.SilkS")
			(effects
				(font
					(size 1.27 0.9652)
					(thickness 0.1524)
				)
			)
		)
		(property "Value" ""
			(at 0 0 90)
			(layer "F.Fab")
			(effects
				(font
					(size 1.27 1.27)
				)
			)
		)
		(duplicate_pad_numbers_are_jumpers no)
		(fp_rect
			(start -0.500126 1.598422)
			(end 0.500126 -0.201422)
			(stroke
				(width 0)
				(type default)
			)
			(fill no)
			(layer "F.CrtYd")
		)
		(fp_line
			(start 0.500126 -0.201422)
			(end 0.500126 1.598422)
			(stroke
				(width 0.1)
				(type default)
			)
			(layer "F.Fab")
		)
		(fp_line
			(start -0.500126 -0.201422)
			(end 0.500126 -0.201422)
			(stroke
				(width 0.1)
				(type default)
			)
			(layer "F.Fab")
		)
		(fp_line
			(start 0.500126 1.598422)
			(end -0.500126 1.598422)
			(stroke
				(width 0.1)
				(type default)
			)
			(layer "F.Fab")
		)
		(fp_line
			(start -0.500126 1.598422)
			(end -0.500126 -0.201422)
			(stroke
				(width 0.1)
				(type default)
			)
			(layer "F.Fab")
		)
		(pad "1" smd rect
			(at 0 0)
			(size 0.889 0.9906)
			(layers "F.Cu" "F.Mask" "F.Paste")
			(net "PVDDQ_ABC")
		)
		(pad "2" smd rect
			(at 0 1.397)
			(size 0.889 0.9906)
			(layers "F.Cu" "F.Mask" "F.Paste")
			(net "GND")
		)
		(zone
			(layer "F.Cu")
			(hatch none 0.5)
			(connect_pads
				(clearance 0)
			)
			(min_thickness 0.25)
			(keepout
				(tracks allowed)
				(vias not_allowed)
				(pads allowed)
				(copperpour not_allowed)
				(footprints allowed)
			)
			(placement
				(enabled no)
				(sheetname "")
			)
			(fill
				(thermal_gap 0.5)
				(thermal_bridge_width 0.5)
				(island_removal_mode 0)
			)
			(polygon
				(pts
					(xy 254.344932 -12.4587) (xy 254.344932 -13.4493) (xy 253.836932 -13.4493) (xy 253.836932 -12.4587)
				)
			)
		)
		(zone
			(layer "F.Cu")
			(hatch none 0.5)
			(connect_pads
				(clearance 0)
			)
			(min_thickness 0.25)
			(keepout
				(tracks not_allowed)
				(vias allowed)
				(pads allowed)
				(copperpour not_allowed)
				(footprints allowed)
			)
			(placement
				(enabled no)
				(sheetname "")
			)
			(fill
				(thermal_gap 0.5)
				(thermal_bridge_width 0.5)
				(island_removal_mode 0)
			)
			(polygon
				(pts
					(xy 254.344932 -12.4587) (xy 254.344932 -13.4493) (xy 253.836932 -13.4493) (xy 253.836932 -12.4587)
				)
			)
		)
	)
	(footprint ""
		(layer "F.Cu")
		(at 407.753566 -95.687642 -90)
		(property "Reference" "C8C13"
			(at -0.8382 -0.67818 270)
			(unlocked yes)
			(layer "F.SilkS")
			(effects
				(font
					(size 0.4064 0.254)
					(thickness 0.1524)
				)
				(justify left)
			)
		)
		(property "Value" ""
			(at 0 0 270)
			(layer "F.Fab")
			(effects
				(font
					(size 1.27 1.27)
				)
			)
		)
		(duplicate_pad_numbers_are_jumpers no)
		(fp_poly
			(pts
				(xy 0.3048 -0.1016) (xy 0.3048 0.9906) (xy -0.3048 0.9906) (xy -0.3048 -0.1016)
			)
			(stroke
				(width 0)
				(type default)
			)
			(fill no)
			(layer "F.CrtYd")
		)
		(fp_line
			(start -0.3048 0.9906)
			(end 0.3048 0.9906)
			(stroke
				(width 0.1)
				(type default)
			)
			(layer "F.Fab")
		)
		(fp_line
			(start 0.3048 0.9906)
			(end 0.3048 -0.1016)
			(stroke
				(width 0.1)
				(type default)
			)
			(layer "F.Fab")
		)
		(fp_line
			(start -0.3048 -0.1016)
			(end -0.3048 0.9906)
			(stroke
				(width 0.1)
				(type default)
			)
			(layer "F.Fab")
		)
		(fp_line
			(start 0.3048 -0.1016)
			(end -0.3048 -0.1016)
			(stroke
				(width 0.1)
				(type default)
			)
			(layer "F.Fab")
		)
		(pad "1" smd rect
			(at 0 0 270)
			(size 0.508 0.508)
			(layers "F.Cu" "F.Mask" "F.Paste")
			(net "KR_P1_OCP_RX_DN")
		)
		(pad "2" smd rect
			(at 0 0.889 270)
			(size 0.508 0.508)
			(layers "F.Cu" "F.Mask" "F.Paste")
			(net "KR_P1_OCP_RX_C_DN")
		)
		(zone
			(layer "F.Cu")
			(hatch none 0.5)
			(connect_pads
				(clearance 0)
			)
			(min_thickness 0.25)
			(keepout
				(tracks not_allowed)
				(vias allowed)
				(pads allowed)
				(copperpour not_allowed)
				(footprints allowed)
			)
			(placement
				(enabled no)
				(sheetname "")
			)
			(fill
				(thermal_gap 0.5)
				(thermal_bridge_width 0.5)
				(island_removal_mode 0)
			)
			(polygon
				(pts
					(xy 407.118566 -95.941642) (xy 407.118566 -95.433642) (xy 407.499566 -95.433642) (xy 407.499566 -95.941642)
				)
			)
		)
		(zone
			(layer "F.Cu")
			(hatch none 0.5)
			(connect_pads
				(clearance 0)
			)
			(min_thickness 0.25)
			(keepout
				(tracks allowed)
				(vias not_allowed)
				(pads allowed)
				(copperpour not_allowed)
				(footprints allowed)
			)
			(placement
				(enabled no)
				(sheetname "")
			)
			(fill
				(thermal_gap 0.5)
				(thermal_bridge_width 0.5)
				(island_removal_mode 0)
			)
			(polygon
				(pts
					(xy 407.499566 -95.941642) (xy 407.499566 -95.433642) (xy 407.118566 -95.433642) (xy 407.118566 -95.941642)
				)
			)
		)
	)
	(footprint ""
		(layer "F.Cu")
		(at 33.240726 -93.787214 90)
		(property "Reference" "C1C4"
			(at 0 0 90)
			(layer "F.SilkS")
			(hide yes)
			(effects
				(font
					(size 1.27 1.27)
				)
			)
		)
		(property "Value" ""
			(at 0 0 90)
			(layer "F.Fab")
			(effects
				(font
					(size 1.27 1.27)
				)
			)
		)
		(duplicate_pad_numbers_are_jumpers no)
		(fp_rect
			(start 0.3048 0.9906)
			(end -0.3048 -0.1016)
			(stroke
				(width 0)
				(type default)
			)
			(fill no)
			(layer "F.CrtYd")
		)
		(fp_line
			(start 0.3048 -0.1016)
			(end -0.3048 -0.1016)
			(stroke
				(width 0.1)
				(type default)
			)
			(layer "F.Fab")
		)
		(fp_line
			(start -0.3048 -0.1016)
			(end -0.3048 0.9906)
			(stroke
				(width 0.1)
				(type default)
			)
			(layer "F.Fab")
		)
		(fp_line
			(start 0.3048 0.9906)
			(end 0.3048 -0.1016)
			(stroke
				(width 0.1)
				(type default)
			)
			(layer "F.Fab")
		)
		(fp_line
			(start -0.3048 0.9906)
			(end 0.3048 0.9906)
			(stroke
				(width 0.1)
				(type default)
			)
			(layer "F.Fab")
		)
		(pad "1" smd rect
			(at 0 0 90)
			(size 0.508 0.508)
			(layers "F.Cu" "F.Mask" "F.Paste")
			(net "P5V_STBY")
		)
		(pad "2" smd rect
			(at 0 0.889 90)
			(size 0.508 0.508)
			(layers "F.Cu" "F.Mask" "F.Paste")
			(net "GND")
		)
		(zone
			(layer "F.Cu")
			(hatch none 0.5)
			(connect_pads
				(clearance 0)
			)
			(min_thickness 0.25)
			(keepout
				(tracks allowed)
				(vias not_allowed)
				(pads allowed)
				(copperpour not_allowed)
				(footprints allowed)
			)
			(placement
				(enabled no)
				(sheetname "")
			)
			(fill
				(thermal_gap 0.5)
				(thermal_bridge_width 0.5)
				(island_removal_mode 0)
			)
			(polygon
				(pts
					(xy 33.875726 -94.041214) (xy 33.494726 -94.041214) (xy 33.494726 -93.533214) (xy 33.875726 -93.533214)
				)
			)
		)
		(zone
			(layer "F.Cu")
			(hatch none 0.5)
			(connect_pads
				(clearance 0)
			)
			(min_thickness 0.25)
			(keepout
				(tracks not_allowed)
				(vias allowed)
				(pads allowed)
				(copperpour not_allowed)
				(footprints allowed)
			)
			(placement
				(enabled no)
				(sheetname "")
			)
			(fill
				(thermal_gap 0.5)
				(thermal_bridge_width 0.5)
				(island_removal_mode 0)
			)
			(polygon
				(pts
					(xy 33.875726 -94.041214) (xy 33.494726 -94.041214) (xy 33.494726 -93.533214) (xy 33.875726 -93.533214)
				)
			)
		)
	)
	(footprint ""
		(layer "F.Cu")
		(at 35.7886 -52.9082 -90)
		(property "Reference" "RT16"
			(at 0 0 270)
			(layer "F.SilkS")
			(hide yes)
			(effects
				(font
					(size 1.27 1.27)
				)
			)
		)
		(property "Value" "*"
			(at -0.0254 -2.6289 270)
			(unlocked yes)
			(layer "F.Fab")
			(hide yes)
			(effects
				(font
					(size 1.27 1.016)
					(thickness 0.1524)
				)
			)
		)
		(property "Device Type" "1R3F-GP_RCL_GP-1R3F-GP,64.1R00A"
			(at -0.0254 -4.1529 270)
			(unlocked yes)
			(layer "F.Fab")
			(hide yes)
			(effects
				(font
					(size 1.27 1.016)
					(thickness 0.1524)
				)
			)
		)
		(duplicate_pad_numbers_are_jumpers no)
		(fp_line
			(start -0.4826 0)
			(end -0.2032 0)
			(stroke
				(width 0.2032)
				(type default)
			)
			(layer "F.SilkS")
		)
		(fp_line
			(start 0.2032 0)
			(end 0.4826 0)
			(stroke
				(width 0.2032)
				(type default)
			)
			(layer "F.SilkS")
		)
		(fp_rect
			(start -0.5842 1.3335)
			(end 0.5842 -1.3335)
			(stroke
				(width 0)
				(type default)
			)
			(fill no)
			(layer "F.CrtYd")
		)
		(fp_rect
			(start -0.5842 1.3335)
			(end 0.5842 -1.3335)
			(stroke
				(width 0)
				(type default)
			)
			(fill no)
			(layer "F.Fab")
		)
		(pad "1" smd custom
			(at 0 -0.762 270)
			(size 0.2159 0.2159)
			(layers "F.Cu" "F.Mask" "F.Paste")
			(net "VR_PVCCIN_CPU1_PHASE1_RC")
			(options
				(clearance outline)
				(anchor circle)
			)
			(primitives
				(gr_poly
					(pts
						(arc
							(start -0.3302 -0.4318)
							(mid -0.402042 -0.402042)
							(end -0.4318 -0.3302)
						)
						(arc
							(start -0.4318 0.3302)
							(mid -0.402042 0.402042)
							(end -0.3302 0.4318)
						)
						(arc
							(start 0.3302 0.4318)
							(mid 0.402042 0.402042)
							(end 0.4318 0.3302)
						)
						(arc
							(start 0.4318 -0.3302)
							(mid 0.402042 -0.402042)
							(end 0.3302 -0.4318)
						)
					)
					(width 0)
					(fill yes)
				)
			)
		)
		(pad "2" smd custom
			(at 0 0.762 270)
			(size 0.2159 0.2159)
			(layers "F.Cu" "F.Mask" "F.Paste")
			(net "GND")
			(options
				(clearance outline)
				(anchor circle)
			)
			(primitives
				(gr_poly
					(pts
						(arc
							(start -0.3302 -0.4318)
							(mid -0.402042 -0.402042)
							(end -0.4318 -0.3302)
						)
						(arc
							(start -0.4318 0.3302)
							(mid -0.402042 0.402042)
							(end -0.3302 0.4318)
						)
						(arc
							(start 0.3302 0.4318)
							(mid 0.402042 0.402042)
							(end 0.4318 0.3302)
						)
						(arc
							(start 0.4318 -0.3302)
							(mid 0.402042 -0.402042)
							(end 0.3302 -0.4318)
						)
					)
					(width 0)
					(fill yes)
				)
			)
		)
	)
	(footprint ""
		(layer "F.Cu")
		(at 145.415 -26.67)
		(property "Reference" ""
			(at 0 0 0)
			(layer "F.SilkS")
			(hide yes)
			(effects
				(font
					(size 1.27 1.27)
				)
			)
		)
		(property "Value" ""
			(at 0 0 0)
			(layer "F.Fab")
			(effects
				(font
					(size 1.27 1.27)
				)
			)
		)
		(duplicate_pad_numbers_are_jumpers no)
		(fp_poly
			(pts
				(arc
					(start 2.032 0)
					(mid -2.032 0)
					(end 2.032 0)
				)
			)
			(stroke
				(width 0)
				(type default)
			)
			(fill no)
			(layer "F.CrtYd")
		)
		(pad "1" smd circle
			(at 0 0)
			(size 1.016 1.016)
			(layers "F.Cu" "F.Mask" "F.Paste")
			(net "Net_389")
		)
		(zone
			(layer "F.Cu")
			(hatch none 0.5)
			(connect_pads
				(clearance 0)
			)
			(min_thickness 0.25)
			(keepout
				(tracks not_allowed)
				(vias allowed)
				(pads allowed)
				(copperpour not_allowed)
				(footprints allowed)
			)
			(placement
				(enabled no)
				(sheetname "")
			)
			(fill
				(thermal_gap 0.5)
				(thermal_bridge_width 0.5)
				(island_removal_mode 0)
			)
			(polygon
				(pts
					(arc
						(start 146.939 -26.67)
						(mid 143.891 -26.67)
						(end 146.939 -26.67)
					)
				)
			)
		)
		(zone
			(layers "F.Cu" "B.Cu" "In1.Cu" "In2.Cu" "In3.Cu" "In4.Cu" "In5.Cu" "In6.Cu"
				"In7.Cu" "In8.Cu" "In9.Cu" "In10.Cu" "In11.Cu" "In12.Cu"
			)
			(hatch none 0.5)
			(connect_pads
				(clearance 0)
			)
			(min_thickness 0.25)
			(keepout
				(tracks allowed)
				(vias not_allowed)
				(pads allowed)
				(copperpour not_allowed)
				(footprints allowed)
			)
			(placement
				(enabled no)
				(sheetname "")
			)
			(fill
				(thermal_gap 0.5)
				(thermal_bridge_width 0.5)
				(island_removal_mode 0)
			)
			(polygon
				(pts
					(arc
						(start 146.939 -26.67)
						(mid 143.891 -26.67)
						(end 146.939 -26.67)
					)
				)
			)
		)
	)
	(footprint ""
		(layer "F.Cu")
		(at 88.392 -12.954 90)
		(property "Reference" "C2G4"
			(at 1.848866 0.752348 90)
			(unlocked yes)
			(layer "F.SilkS")
			(effects
				(font
					(size 1.27 0.9652)
					(thickness 0.1524)
				)
			)
		)
		(property "Value" ""
			(at 0 0 90)
			(layer "F.Fab")
			(effects
				(font
					(size 1.27 1.27)
				)
			)
		)
		(duplicate_pad_numbers_are_jumpers no)
		(fp_rect
			(start -0.500126 1.598422)
			(end 0.500126 -0.201422)
			(stroke
				(width 0)
				(type default)
			)
			(fill no)
			(layer "F.CrtYd")
		)
		(fp_line
			(start 0.500126 -0.201422)
			(end 0.500126 1.598422)
			(stroke
				(width 0.1)
				(type default)
			)
			(layer "F.Fab")
		)
		(fp_line
			(start -0.500126 -0.201422)
			(end 0.500126 -0.201422)
			(stroke
				(width 0.1)
				(type default)
			)
			(layer "F.Fab")
		)
		(fp_line
			(start 0.500126 1.598422)
			(end -0.500126 1.598422)
			(stroke
				(width 0.1)
				(type default)
			)
			(layer "F.Fab")
		)
		(fp_line
			(start -0.500126 1.598422)
			(end -0.500126 -0.201422)
			(stroke
				(width 0.1)
				(type default)
			)
			(layer "F.Fab")
		)
		(pad "1" smd rect
			(at 0 0)
			(size 0.889 0.9906)
			(layers "F.Cu" "F.Mask" "F.Paste")
			(net "PVDDQ_GHJ")
		)
		(pad "2" smd rect
			(at 0 1.397)
			(size 0.889 0.9906)
			(layers "F.Cu" "F.Mask" "F.Paste")
			(net "GND")
		)
		(zone
			(layer "F.Cu")
			(hatch none 0.5)
			(connect_pads
				(clearance 0)
			)
			(min_thickness 0.25)
			(keepout
				(tracks allowed)
				(vias not_allowed)
				(pads allowed)
				(copperpour not_allowed)
				(footprints allowed)
			)
			(placement
				(enabled no)
				(sheetname "")
			)
			(fill
				(thermal_gap 0.5)
				(thermal_bridge_width 0.5)
				(island_removal_mode 0)
			)
			(polygon
				(pts
					(xy 89.3445 -12.4587) (xy 89.3445 -13.4493) (xy 88.8365 -13.4493) (xy 88.8365 -12.4587)
				)
			)
		)
		(zone
			(layer "F.Cu")
			(hatch none 0.5)
			(connect_pads
				(clearance 0)
			)
			(min_thickness 0.25)
			(keepout
				(tracks not_allowed)
				(vias allowed)
				(pads allowed)
				(copperpour not_allowed)
				(footprints allowed)
			)
			(placement
				(enabled no)
				(sheetname "")
			)
			(fill
				(thermal_gap 0.5)
				(thermal_bridge_width 0.5)
				(island_removal_mode 0)
			)
			(polygon
				(pts
					(xy 89.3445 -12.4587) (xy 89.3445 -13.4493) (xy 88.8365 -13.4493) (xy 88.8365 -12.4587)
				)
			)
		)
	)
)
